# BASEBOARD_FAB2 (Tioga Pass) — schematic netlist excerpt (pin names and nets, part order shuffled) for the footprints in the layout excerpt that follows; sources: Cadence DE-HDL packaged netlist, KiCad conversion of Wiwynn_Tioga_Pass_MB.brd

J9U2  SCONN288_H44441003  SCONN  pkg PIP  page 82
  \12v\(1)  = P12V_NVDIMM_GHJ
  VSS(93)  = GND
  DQ(4)  = M_J_DQ<4>
  VSS(92)  = GND
  DQ(0)  = M_J_DQ<0>
  VSS(91)  = GND
  DQS9P  = M_J_DQS_DP<9>
  DQS9N  = M_J_DQS_DN<9>
  VSS(90)  = GND
  DQ(6)  = M_J_DQ<6>
  VSS(89)  = GND
  DQ(2)  = M_J_DQ<2>
  VSS(88)  = GND
  DQ(12)  = M_J_DQ<12>
  VSS(87)  = GND
  DQ(8)  = M_J_DQ<8>
  VSS(86)  = GND
  DQS10P  = M_J_DQS_DP<10>
  DQS10N  = M_J_DQS_DN<10>
  VSS(85)  = GND
  DQ(14)  = M_J_DQ<14>
  VSS(84)  = GND
  DQ(10)  = M_J_DQ<10>
  VSS(83)  = GND
  DQ(20)  = M_J_DQ<20>
  VSS(82)  = GND
  DQ(16)  = M_J_DQ<16>
  VSS(81)  = GND
  DQS11P  = M_J_DQS_DP<11>
  DQS11N  = M_J_DQS_DN<11>
  VSS(80)  = GND
  DQ(22)  = M_J_DQ<22>
  VSS(79)  = GND
  DQ(18)  = M_J_DQ<18>
  VSS(78)  = GND
  DQ(28)  = M_J_DQ<28>
  VSS(77)  = GND
  DQ(24)  = M_J_DQ<24>
  VSS(76)  = GND
  DQS12P  = M_J_DQS_DP<12>
  DQS12N  = M_J_DQS_DN<12>
  VSS(75)  = GND
  DQ(30)  = M_J_DQ<30>
  VSS(74)  = GND
  DQ(26)  = M_J_DQ<26>
  VSS(73)  = GND
  CB(4)  = M_J_ECC<4>
  VSS(72)  = GND
  CB(0)  = M_J_ECC<0>
  VSS(71)  = GND
  DQS17P  = M_J_DQS_DP<17>
  DQS17N  = M_J_DQS_DN<17>
  VSS(70)  = GND
  CB(6)  = M_J_ECC<6>
  VSS(69)  = GND
  CB(2)  = M_J_ECC<2>
  VSS(68)  = GND
  RESET_N  = M_GHJ_RST_N
  VDD(25)  = PVDDQ_GHJ
  CKE(0)  = M_J_CKE<2>
  VDD(24)  = PVDDQ_GHJ
  ACT_N  = M_J_ACT_N
  BG(0)  = M_J_BG<0>
  VDD(23)  = PVDDQ_GHJ
  A12  = M_J_MA<12>
  A9  = M_J_MA<9>
  VDD(22)  = PVDDQ_GHJ
  A8  = M_J_MA<8>
  A6  = M_J_MA<6>
  VDD(21)  = PVDDQ_GHJ
  A3  = M_J_MA<3>
  A1  = M_J_MA<1>
  VDD(20)  = PVDDQ_GHJ
  CK0P  = M_J_CLK_DP<2>
  CK0N  = M_J_CLK_DN<2>
  VDD(19)  = PVDDQ_GHJ
  VTT(1)  = PVTT_GHJ
  EVENT_N  = FM_DIMM_EVENT_COD_N
  A0  = M_J_MA<0>
  VDD(18)  = PVDDQ_GHJ
  BA(0)  = M_J_BA<0>
  A16_RAS_N  = M_J_MA<16>
  VDD(17)  = PVDDQ_GHJ
  S0_N  = M_J_CS_N<4>
  VDD(16)  = PVDDQ_GHJ
  A15_CAS_N  = M_J_MA<15>
  ODT(0)  = M_J_ODT<2>
  VDD(15)  = PVDDQ_GHJ
  S1_N  = M_J_CS_N<5>
  VDD(14)  = PVDDQ_GHJ
  ODT(1)  = M_J_ODT<3>
  VDD(13)  = PVDDQ_GHJ
  S2_N_C(0)  = M_J_CS_N<6>
  VSS(67)  = GND
  DQ(36)  = M_J_DQ<36>
  VSS(66)  = GND
  DQ(32)  = M_J_DQ<32>
  VSS(65)  = GND
  DQS13P  = M_J_DQS_DP<13>
  DQS13N  = M_J_DQS_DN<13>
  VSS(64)  = GND
  DQ(38)  = M_J_DQ<38>
  VSS(63)  = GND
  DQ(34)  = M_J_DQ<34>
  VSS(62)  = GND
  DQ(44)  = M_J_DQ<44>
  VSS(61)  = GND
  DQ(40)  = M_J_DQ<40>
  VSS(60)  = GND
  DQS14P  = M_J_DQS_DP<14>
  DQS14N  = M_J_DQS_DN<14>
  VSS(59)  = GND
  DQ(46)  = M_J_DQ<46>
  VSS(58)  = GND
  DQ(42)  = M_J_DQ<42>
  VSS(57)  = GND
  DQ(52)  = M_J_DQ<52>
  VSS(56)  = GND
  DQ(48)  = M_J_DQ<48>
  VSS(55)  = GND
  DQS15P  = M_J_DQS_DP<15>
  DQS15N  = M_J_DQS_DN<15>
  VSS(54)  = GND
  DQ(54)  = M_J_DQ<54>
  VSS(53)  = GND
  DQ(50)  = M_J_DQ<50>
  VSS(52)  = GND
  DQ(60)  = M_J_DQ<60>
  VSS(51)  = GND
  DQ(56)  = M_J_DQ<56>
  VSS(50)  = GND
  DQS16P  = M_J_DQS_DP<16>
  DQS16N  = M_J_DQS_DN<16>
  VSS(49)  = GND
  DQ(62)  = M_J_DQ<62>
  VSS(48)  = GND
  DQ(58)  = M_J_DQ<58>
  VSS(47)  = GND
  SA(0)  = PVPP_GHJ
  SA(1)  = GND
  SCL  = SMB_DDR_GHJ_VPP_SCL
  VPP(4)  = PVPP_GHJ
  VPP(3)  = PVPP_GHJ
  RFU(2)  = TP_CH_J_DIMM_J1_RFU_2
  \12v\(0)  = P12V_NVDIMM_GHJ
  VREFCA  = M_J_VREF
  VSS(46)  = GND
  DQ(5)  = M_J_DQ<5>
  VSS(45)  = GND
  DQ(1)  = M_J_DQ<1>
  VSS(44)  = GND
  DQS0N  = M_J_DQS_DN<0>
  DQS0P  = M_J_DQS_DP<0>
  VSS(43)  = GND
  DQ(7)  = M_J_DQ<7>
  VSS(42)  = GND
  DQ(3)  = M_J_DQ<3>
  VSS(41)  = GND
  DQ(13)  = M_J_DQ<13>
  VSS(40)  = GND
  DQ(9)  = M_J_DQ<9>
  VSS(39)  = GND
  DQS1N  = M_J_DQS_DN<1>
  DQS1P  = M_J_DQS_DP<1>
  VSS(38)  = GND
  DQ(15)  = M_J_DQ<15>
  VSS(37)  = GND
  DQ(11)  = M_J_DQ<11>
  VSS(36)  = GND
  DQ(21)  = M_J_DQ<21>
  VSS(35)  = GND
  DQ(17)  = M_J_DQ<17>
  VSS(34)  = GND
  DQS2N  = M_J_DQS_DN<2>
  DQS2P  = M_J_DQS_DP<2>
  VSS(33)  = GND
  DQ(23)  = M_J_DQ<23>
  VSS(32)  = GND
  DQ(19)  = M_J_DQ<19>
  VSS(31)  = GND
  DQ(29)  = M_J_DQ<29>
  VSS(30)  = GND
  DQ(25)  = M_J_DQ<25>
  VSS(29)  = GND
  DQS3N  = M_J_DQS_DN<3>
  DQS3P  = M_J_DQS_DP<3>
  VSS(28)  = GND
  DQ(31)  = M_J_DQ<31>
  VSS(27)  = GND
  DQ(27)  = M_J_DQ<27>
  VSS(26)  = GND
  CB(5)  = M_J_ECC<5>
  VSS(25)  = GND
  CB(1)  = M_J_ECC<1>
  VSS(24)  = GND
  DQS8N  = M_J_DQS_DN<8>
  DQS8P  = M_J_DQS_DP<8>
  VSS(23)  = GND
  CB(7)  = M_J_ECC<7>
  VSS(22)  = GND
  CB(3)  = M_J_ECC<3>
  VSS(21)  = GND
  CKE(1)  = M_J_CKE<3>
  VDD(12)  = PVDDQ_GHJ
  RFU(0)  = TP_CH_J_DIMM_J1_RFU_0
  VDD(11)  = PVDDQ_GHJ
  BG(1)  = M_J_BG<1>
  ALERT_N  = M_J_ALERT_N
  VDD(10)  = PVDDQ_GHJ
  A11  = M_J_MA<11>
  A7  = M_J_MA<7>
  VDD(9)  = PVDDQ_GHJ
  A5  = M_J_MA<5>
  A4  = M_J_MA<4>
  VDD(8)  = PVDDQ_GHJ
  A2  = M_J_MA<2>
  VDD(7)  = PVDDQ_GHJ
  CK1P  = M_J_CLK_DP<3>
  CK1N  = M_J_CLK_DN<3>
  VDD(6)  = PVDDQ_GHJ
  VTT(0)  = PVTT_GHJ
  PAR  = M_J_PAR
  VDD(5)  = PVDDQ_GHJ
  BA(1)  = M_J_BA<1>
  A10  = M_J_MA<10>
  VDD(4)  = PVDDQ_GHJ
  RFU(1)  = TP_CH_J_DIMM_J1_RFU_1
  A14_WE_N  = M_J_MA<14>
  VDD(3)  = PVDDQ_GHJ
  SAVE_N_NC  = FM_ADR_COMPLETE_GHJ_N
  VDD(2)  = PVDDQ_GHJ
  A13  = M_J_MA<13>
  VDD(1)  = PVDDQ_GHJ
  A17  = M_J_MA<17>
  C(2)  = M_J_C<2>
  VDD(0)  = PVDDQ_GHJ
  S3_N_C(1)  = M_J_CS_N<7>
  SA(2)  = PVPP_GHJ
  VSS(20)  = GND
  DQ(37)  = M_J_DQ<37>
  VSS(19)  = GND
  DQ(33)  = M_J_DQ<33>
  VSS(18)  = GND
  DQS4N  = M_J_DQS_DN<4>
  DQS4P  = M_J_DQS_DP<4>
  VSS(17)  = GND
  DQ(39)  = M_J_DQ<39>
  VSS(16)  = GND
  DQ(35)  = M_J_DQ<35>
  VSS(15)  = GND
  DQ(45)  = M_J_DQ<45>
  VSS(14)  = GND
  DQ(41)  = M_J_DQ<41>
  VSS(13)  = GND
  DQS5N  = M_J_DQS_DN<5>
  DQS5P  = M_J_DQS_DP<5>
  VSS(12)  = GND
  DQ(47)  = M_J_DQ<47>
  VSS(11)  = GND
  DQ(43)  = M_J_DQ<43>
  VSS(10)  = GND
  DQ(53)  = M_J_DQ<53>
  VSS(9)  = GND
  DQ(49)  = M_J_DQ<49>
  VSS(8)  = GND
  DQS6N  = M_J_DQS_DN<6>
  DQS6P  = M_J_DQS_DP<6>
  VSS(7)  = GND
  DQ(55)  = M_J_DQ<55>
  VSS(6)  = GND
  DQ(51)  = M_J_DQ<51>
  VSS(5)  = GND
  DQ(61)  = M_J_DQ<61>
  VSS(4)  = GND
  DQ(57)  = M_J_DQ<57>
  VSS(3)  = GND
  DQS7N  = M_J_DQS_DN<7>
  DQS7P  = M_J_DQS_DP<7>
  VSS(2)  = GND
  DQ(63)  = M_J_DQ<63>
  VSS(1)  = GND
  DQ(59)  = M_J_DQ<59>
  VSS(0)  = GND
  VDDSPD  = PVPP_GHJ
  SDA  = SMB_DDR_GHJ_VPP_SDA
  VPP(1)  = PVPP_GHJ
  VPP(0)  = PVPP_GHJ
  VPP(2)  = PVPP_GHJ

(kicad_pcb
	(version 20260206)
	(generator "pcbnew")
	(generator_version "10.0")
	(general
		(thickness 1.6)
		(legacy_teardrops no)
	)
	(paper "A4")
	(title_block
		(title "Wiwynn_Tioga_Pass_MB.brd")
		(comment 1 "Tioga Pass / footprint 4543 of 4770 (J9U2), pads 202-249 of 291")
	)
	(layers
		(0 "F.Cu" signal "TOP")
		(4 "In1.Cu" signal "L2GND")
		(6 "In2.Cu" signal "L3")
		(8 "In3.Cu" signal "L4GND")
		(10 "In4.Cu" signal "L5")
		(12 "In5.Cu" signal "L6GND")
		(14 "In6.Cu" signal "L7VCC")
		(16 "In7.Cu" signal "L8VCC")
		(18 "In8.Cu" signal "L9GND")
		(20 "In9.Cu" signal "L10")
		(22 "In10.Cu" signal "L11GND")
		(24 "In11.Cu" signal "L12")
		(26 "In12.Cu" signal "L13GND")
		(2 "B.Cu" signal "BOTTOM")
		(9 "F.Adhes" user "F.Adhesive")
		(11 "B.Adhes" user "B.Adhesive")
		(13 "F.Paste" user "Package Geometry/Pastemask Top")
		(15 "B.Paste" user "Package Geometry/Pastemask Bottom")
		(5 "F.SilkS" user "Ref Des/Silkscreen Top")
		(7 "B.SilkS" user "Ref Des/Silkscreen Bottom")
		(1 "F.Mask" user "Board Geometry/Soldermask Top")
		(3 "B.Mask" user "Board Geometry/Soldermask Bottom")
		(17 "Dwgs.User" user "User.Drawings")
		(19 "Cmts.User" user "User.Comments")
		(21 "Eco1.User" user "User.Eco1")
		(23 "Eco2.User" user "User.Eco2")
		(25 "Edge.Cuts" user "Board Geometry/Outline")
		(27 "Margin" user)
		(31 "F.CrtYd" user "Package Geometry/Place Bound Top")
		(29 "B.CrtYd" user "Package Geometry/Place Bound Bottom")
		(35 "F.Fab" user "Ref Des/Assembly Top")
		(33 "B.Fab" user "Ref Des/Assembly Bottom")
	)
	(footprint ""
		(layer "B.Cu")
		(at 29.699458 -5.621782 90)
		(property "Reference" "J9U2"
			(at 2.098548 38.118542 0)
			(unlocked yes)
			(layer "B.SilkS")
			(effects
				(font
					(size 0.7874 0.5842)
					(thickness 0.1524)
				)
				(justify left mirror)
			)
		)
		(property "Value" ""
			(at 0 0 90)
			(layer "B.Fab")
			(effects
				(font
					(size 1.27 1.27)
				)
				(justify mirror)
			)
		)
		(duplicate_pad_numbers_are_jumpers no)
		(pad "199" smd rect
			(at -4.59994 45.900086 270)
			(size 1.8034 0.508)
			(layers "B.Cu" "B.Mask" "B.Paste")
			(net "M_J_ECC<7>")
		)
		(pad "200" smd rect
			(at -4.59994 46.74997 270)
			(size 1.8034 0.508)
			(layers "B.Cu" "B.Mask" "B.Paste")
			(net "GND")
		)
		(pad "201" smd rect
			(at -4.59994 47.600108 270)
			(size 1.8034 0.508)
			(layers "B.Cu" "B.Mask" "B.Paste")
			(net "M_J_ECC<3>")
		)
		(pad "202" smd rect
			(at -4.59994 48.449992 270)
			(size 1.8034 0.508)
			(layers "B.Cu" "B.Mask" "B.Paste")
			(net "GND")
		)
		(pad "203" smd rect
			(at -4.59994 49.299876 270)
			(size 1.8034 0.508)
			(layers "B.Cu" "B.Mask" "B.Paste")
			(net "M_J_CKE<3>")
		)
		(pad "204" smd rect
			(at -4.59994 50.150014 270)
			(size 1.8034 0.508)
			(layers "B.Cu" "B.Mask" "B.Paste")
			(net "PVDDQ_GHJ")
		)
		(pad "205" smd rect
			(at -4.59994 50.999898 270)
			(size 1.8034 0.508)
			(layers "B.Cu" "B.Mask" "B.Paste")
			(net "TP_CH_J_DIMM_J1_RFU_0")
		)
		(pad "206" smd rect
			(at -4.59994 51.850036 270)
			(size 1.8034 0.508)
			(layers "B.Cu" "B.Mask" "B.Paste")
			(net "PVDDQ_GHJ")
		)
		(pad "207" smd rect
			(at -4.59994 52.69992 270)
			(size 1.8034 0.508)
			(layers "B.Cu" "B.Mask" "B.Paste")
			(net "M_J_BG<1>")
		)
		(pad "208" smd rect
			(at -4.59994 53.550058 270)
			(size 1.8034 0.508)
			(layers "B.Cu" "B.Mask" "B.Paste")
			(net "M_J_ALERT_N")
		)
		(pad "209" smd rect
			(at -4.59994 54.399942 270)
			(size 1.8034 0.508)
			(layers "B.Cu" "B.Mask" "B.Paste")
			(net "PVDDQ_GHJ")
		)
		(pad "210" smd rect
			(at -4.59994 55.25008 270)
			(size 1.8034 0.508)
			(layers "B.Cu" "B.Mask" "B.Paste")
			(net "M_J_MA<11>")
		)
		(pad "211" smd rect
			(at -4.59994 56.099964 270)
			(size 1.8034 0.508)
			(layers "B.Cu" "B.Mask" "B.Paste")
			(net "M_J_MA<7>")
		)
		(pad "212" smd rect
			(at -4.59994 56.950102 270)
			(size 1.8034 0.508)
			(layers "B.Cu" "B.Mask" "B.Paste")
			(net "PVDDQ_GHJ")
		)
		(pad "213" smd rect
			(at -4.59994 57.799986 270)
			(size 1.8034 0.508)
			(layers "B.Cu" "B.Mask" "B.Paste")
			(net "M_J_MA<5>")
		)
		(pad "214" smd rect
			(at -4.59994 58.650124 270)
			(size 1.8034 0.508)
			(layers "B.Cu" "B.Mask" "B.Paste")
			(net "M_J_MA<4>")
		)
		(pad "215" smd rect
			(at -4.59994 59.500008 270)
			(size 1.8034 0.508)
			(layers "B.Cu" "B.Mask" "B.Paste")
			(net "PVDDQ_GHJ")
		)
		(pad "216" smd rect
			(at -4.59994 60.349892 270)
			(size 1.8034 0.508)
			(layers "B.Cu" "B.Mask" "B.Paste")
			(net "M_J_MA<2>")
		)
		(pad "217" smd rect
			(at -4.59994 61.20003 270)
			(size 1.8034 0.508)
			(layers "B.Cu" "B.Mask" "B.Paste")
			(net "PVDDQ_GHJ")
		)
		(pad "218" smd rect
			(at -4.59994 62.049914 270)
			(size 1.8034 0.508)
			(layers "B.Cu" "B.Mask" "B.Paste")
			(net "M_J_CLK_DP<3>")
		)
		(pad "219" smd rect
			(at -4.59994 62.900052 270)
			(size 1.8034 0.508)
			(layers "B.Cu" "B.Mask" "B.Paste")
			(net "M_J_CLK_DN<3>")
		)
		(pad "220" smd rect
			(at -4.59994 63.749936 270)
			(size 1.8034 0.508)
			(layers "B.Cu" "B.Mask" "B.Paste")
			(net "PVDDQ_GHJ")
		)
		(pad "221" smd rect
			(at -4.59994 64.600074 270)
			(size 1.8034 0.508)
			(layers "B.Cu" "B.Mask" "B.Paste")
			(net "PVTT_GHJ")
		)
		(pad "222" smd rect
			(at -4.59994 70.550024 270)
			(size 1.8034 0.508)
			(layers "B.Cu" "B.Mask" "B.Paste")
			(net "M_J_PAR")
		)
		(pad "223" smd rect
			(at -4.59994 71.399908 270)
			(size 1.8034 0.508)
			(layers "B.Cu" "B.Mask" "B.Paste")
			(net "PVDDQ_GHJ")
		)
		(pad "224" smd rect
			(at -4.59994 72.250046 270)
			(size 1.8034 0.508)
			(layers "B.Cu" "B.Mask" "B.Paste")
			(net "M_J_BA<1>")
		)
		(pad "225" smd rect
			(at -4.59994 73.09993 270)
			(size 1.8034 0.508)
			(layers "B.Cu" "B.Mask" "B.Paste")
			(net "M_J_MA<10>")
		)
		(pad "226" smd rect
			(at -4.59994 73.950068 270)
			(size 1.8034 0.508)
			(layers "B.Cu" "B.Mask" "B.Paste")
			(net "PVDDQ_GHJ")
		)
		(pad "227" smd rect
			(at -4.59994 74.799952 270)
			(size 1.8034 0.508)
			(layers "B.Cu" "B.Mask" "B.Paste")
			(net "TP_CH_J_DIMM_J1_RFU_1")
		)
		(pad "228" smd rect
			(at -4.59994 75.65009 270)
			(size 1.8034 0.508)
			(layers "B.Cu" "B.Mask" "B.Paste")
			(net "M_J_MA<14>")
		)
		(pad "229" smd rect
			(at -4.59994 76.499974 270)
			(size 1.8034 0.508)
			(layers "B.Cu" "B.Mask" "B.Paste")
			(net "PVDDQ_GHJ")
		)
		(pad "230" smd rect
			(at -4.59994 77.350112 270)
			(size 1.8034 0.508)
			(layers "B.Cu" "B.Mask" "B.Paste")
			(net "FM_ADR_COMPLETE_GHJ_N")
		)
		(pad "231" smd rect
			(at -4.59994 78.199996 270)
			(size 1.8034 0.508)
			(layers "B.Cu" "B.Mask" "B.Paste")
			(net "PVDDQ_GHJ")
		)
		(pad "232" smd rect
			(at -4.59994 79.04988 270)
			(size 1.8034 0.508)
			(layers "B.Cu" "B.Mask" "B.Paste")
			(net "M_J_MA<13>")
		)
		(pad "233" smd rect
			(at -4.59994 79.900018 270)
			(size 1.8034 0.508)
			(layers "B.Cu" "B.Mask" "B.Paste")
			(net "PVDDQ_GHJ")
		)
		(pad "234" smd rect
			(at -4.59994 80.749902 270)
			(size 1.8034 0.508)
			(layers "B.Cu" "B.Mask" "B.Paste")
			(net "M_J_MA<17>")
		)
		(pad "235" smd rect
			(at -4.59994 81.60004 270)
			(size 1.8034 0.508)
			(layers "B.Cu" "B.Mask" "B.Paste")
			(net "M_J_C<2>")
		)
		(pad "236" smd rect
			(at -4.59994 82.449924 270)
			(size 1.8034 0.508)
			(layers "B.Cu" "B.Mask" "B.Paste")
			(net "PVDDQ_GHJ")
		)
		(pad "237" smd rect
			(at -4.59994 83.300062 270)
			(size 1.8034 0.508)
			(layers "B.Cu" "B.Mask" "B.Paste")
			(net "M_J_CS_N<7>")
		)
		(pad "238" smd rect
			(at -4.59994 84.149946 270)
			(size 1.8034 0.508)
			(layers "B.Cu" "B.Mask" "B.Paste")
			(net "PVPP_GHJ")
		)
		(pad "239" smd rect
			(at -4.59994 85.000084 270)
			(size 1.8034 0.508)
			(layers "B.Cu" "B.Mask" "B.Paste")
			(net "GND")
		)
		(pad "240" smd rect
			(at -4.59994 85.849968 270)
			(size 1.8034 0.508)
			(layers "B.Cu" "B.Mask" "B.Paste")
			(net "M_J_DQ<37>")
		)
		(pad "241" smd rect
			(at -4.59994 86.700106 270)
			(size 1.8034 0.508)
			(layers "B.Cu" "B.Mask" "B.Paste")
			(net "GND")
		)
		(pad "242" smd rect
			(at -4.59994 87.54999 270)
			(size 1.8034 0.508)
			(layers "B.Cu" "B.Mask" "B.Paste")
			(net "M_J_DQ<33>")
		)
		(pad "243" smd rect
			(at -4.59994 88.399874 270)
			(size 1.8034 0.508)
			(layers "B.Cu" "B.Mask" "B.Paste")
			(net "GND")
		)
		(pad "244" smd rect
			(at -4.59994 89.250012 270)
			(size 1.8034 0.508)
			(layers "B.Cu" "B.Mask" "B.Paste")
			(net "M_J_DQS_DN<4>")
		)
		(pad "245" smd rect
			(at -4.59994 90.099896 270)
			(size 1.8034 0.508)
			(layers "B.Cu" "B.Mask" "B.Paste")
			(net "M_J_DQS_DP<4>")
		)
		(pad "246" smd rect
			(at -4.59994 90.950034 270)
			(size 1.8034 0.508)
			(layers "B.Cu" "B.Mask" "B.Paste")
			(net "GND")
		)
	)
)
